# T6G (Grand Teton) — schematic netlist excerpt (pin names and nets, part order shuffled) for the footprints in the layout excerpt that follows; sources: Cadence DE-HDL packaged netlist, KiCad conversion of 04192023_DAF0TMB3IC0_F0TG_MB_C_brd_V02_OCP.brd

PC338  Q_CAP  0.1UF 25V 10% X7R  pkg 0402  page 215 : A = PVDDCR_SOC_P1 ; B = GND
C721  Q_CAP_DIFFBUS  DIFF BUS_0.22UF 6.3V 20% X6S  pkg C0201  page 66 : \1\ = P5E_CPU1_P1_TX_C_DP<10> ; \2\ = P5E_CPU1_P1_TX_DP<10>
R152  Q_RES  33 5% CHIP  pkg 0402LF  page 80 : A = P12V_OCP_SFF_EN ; B = P12V_OCP_SFF_EN_R

(kicad_pcb
	(version 20260206)
	(generator "pcbnew")
	(generator_version "10.0")
	(general
		(thickness 1.6)
		(legacy_teardrops no)
	)
	(paper "A4")
	(title_block
		(title "04192023_DAF0TMB3IC0_F0TG_MB_C_brd_V02_OCP.brd")
		(comment 1 "Grand Teton / footprints 690-692 of 8354")
	)
	(layers
		(0 "F.Cu" signal "TOP")
		(4 "In1.Cu" signal "GND")
		(6 "In2.Cu" signal "IN1")
		(8 "In3.Cu" signal "GND1")
		(10 "In4.Cu" signal "IN2")
		(12 "In5.Cu" signal "GND2")
		(14 "In6.Cu" signal "IN3")
		(16 "In7.Cu" signal "GND3")
		(18 "In8.Cu" signal "VCC")
		(20 "In9.Cu" signal "VCC1")
		(22 "In10.Cu" signal "GND4")
		(24 "In11.Cu" signal "IN4")
		(26 "In12.Cu" signal "GND5")
		(28 "In13.Cu" signal "IN5")
		(30 "In14.Cu" signal "GND6")
		(32 "In15.Cu" signal "IN6")
		(34 "In16.Cu" signal "GND7")
		(2 "B.Cu" signal "BOTTOM")
		(9 "F.Adhes" user "F.Adhesive")
		(11 "B.Adhes" user "B.Adhesive")
		(13 "F.Paste" user "Package Geometry/Pastemask Top")
		(15 "B.Paste" user "Package Geometry/Pastemask Bottom")
		(5 "F.SilkS" user "Ref Des/Silkscreen Top")
		(7 "B.SilkS" user "Ref Des/Silkscreen Bottom")
		(1 "F.Mask" user "Board Geometry/Soldermask Top")
		(3 "B.Mask" user "Board Geometry/Soldermask Bottom")
		(17 "Dwgs.User" user "User.Drawings")
		(19 "Cmts.User" user "User.Comments")
		(21 "Eco1.User" user "User.Eco1")
		(23 "Eco2.User" user "User.Eco2")
		(25 "Edge.Cuts" user "Board Geometry/Outline")
		(27 "Margin" user)
		(31 "F.CrtYd" user "Package Geometry/Place Bound Top")
		(29 "B.CrtYd" user "Package Geometry/Place Bound Bottom")
		(35 "F.Fab" user "Ref Des/Assembly Top")
		(33 "B.Fab" user "Ref Des/Assembly Bottom")
	)
	(footprint ""
		(layer "F.Cu")
		(at 137.186924 -167.9702 -90)
		(property "Reference" "PC338"
			(at 0 0 270)
			(layer "F.SilkS")
			(hide yes)
			(effects
				(font
					(size 1.27 1.27)
				)
			)
		)
		(property "Value" ""
			(at 0 0 270)
			(layer "F.Fab")
			(effects
				(font
					(size 1.27 1.27)
				)
			)
		)
		(duplicate_pad_numbers_are_jumpers no)
		(fp_line
			(start -0.7874 0.4064)
			(end -0.7874 -0.4064)
			(stroke
				(width 0.1524)
				(type default)
			)
			(layer "F.SilkS")
		)
		(fp_line
			(start 0.7874 0.4064)
			(end -0.7874 0.4064)
			(stroke
				(width 0.1524)
				(type default)
			)
			(layer "F.SilkS")
		)
		(fp_line
			(start -0.7874 -0.4064)
			(end 0.7874 -0.4064)
			(stroke
				(width 0.1524)
				(type default)
			)
			(layer "F.SilkS")
		)
		(fp_line
			(start 0.7874 -0.4064)
			(end 0.7874 0.4064)
			(stroke
				(width 0.1524)
				(type default)
			)
			(layer "F.SilkS")
		)
		(fp_line
			(start -0.67945 0.3048)
			(end -0.67945 -0.305054)
			(stroke
				(width 0.1)
				(type default)
			)
			(layer "F.Fab")
		)
		(fp_line
			(start -0.12065 0.3048)
			(end -0.67945 0.3048)
			(stroke
				(width 0.1)
				(type default)
			)
			(layer "F.Fab")
		)
		(fp_line
			(start 0.120396 0.3048)
			(end 0.120396 0.2794)
			(stroke
				(width 0.1)
				(type default)
			)
			(layer "F.Fab")
		)
		(fp_line
			(start 0.67945 0.3048)
			(end 0.120396 0.3048)
			(stroke
				(width 0.1)
				(type default)
			)
			(layer "F.Fab")
		)
		(fp_line
			(start -0.12065 0.2794)
			(end -0.12065 0.3048)
			(stroke
				(width 0.1)
				(type default)
			)
			(layer "F.Fab")
		)
		(fp_line
			(start 0.120396 0.2794)
			(end -0.12065 0.2794)
			(stroke
				(width 0.1)
				(type default)
			)
			(layer "F.Fab")
		)
		(fp_line
			(start -0.12065 -0.2794)
			(end 0.12065 -0.2794)
			(stroke
				(width 0.1)
				(type default)
			)
			(layer "F.Fab")
		)
		(fp_line
			(start 0.12065 -0.2794)
			(end 0.12065 -0.3048)
			(stroke
				(width 0.1)
				(type default)
			)
			(layer "F.Fab")
		)
		(fp_line
			(start 0.12065 -0.3048)
			(end 0.67945 -0.3048)
			(stroke
				(width 0.1)
				(type default)
			)
			(layer "F.Fab")
		)
		(fp_line
			(start 0.67945 -0.3048)
			(end 0.67945 0.3048)
			(stroke
				(width 0.1)
				(type default)
			)
			(layer "F.Fab")
		)
		(fp_line
			(start -0.67945 -0.305054)
			(end -0.12065 -0.305054)
			(stroke
				(width 0.1)
				(type default)
			)
			(layer "F.Fab")
		)
		(fp_line
			(start -0.12065 -0.305054)
			(end -0.12065 -0.2794)
			(stroke
				(width 0.1)
				(type default)
			)
			(layer "F.Fab")
		)
		(pad "1" smd circle
			(at -0.40005 0 270)
			(size 0 0)
			(layers "F.Cu" "F.Mask" "F.Paste")
			(net "PVDDCR_SOC_P1")
		)
		(pad "2" smd circle
			(at 0.40005 0 270)
			(size 0 0)
			(layers "F.Cu" "F.Mask" "F.Paste")
			(net "GND")
		)
	)
	(footprint ""
		(layer "F.Cu")
		(at 167.132 -110.200948 180)
		(property "Reference" "R152"
			(at 0 0 180)
			(layer "F.SilkS")
			(hide yes)
			(effects
				(font
					(size 1.27 1.27)
				)
			)
		)
		(property "Value" ""
			(at 0 0 180)
			(layer "F.Fab")
			(effects
				(font
					(size 1.27 1.27)
				)
			)
		)
		(duplicate_pad_numbers_are_jumpers no)
		(fp_line
			(start 0.7874 0.4064)
			(end -0.7874 0.4064)
			(stroke
				(width 0.1524)
				(type default)
			)
			(layer "F.SilkS")
		)
		(fp_line
			(start 0.7874 -0.4064)
			(end 0.7874 0.4064)
			(stroke
				(width 0.1524)
				(type default)
			)
			(layer "F.SilkS")
		)
		(fp_line
			(start -0.7874 0.4064)
			(end -0.7874 -0.4064)
			(stroke
				(width 0.1524)
				(type default)
			)
			(layer "F.SilkS")
		)
		(fp_line
			(start -0.7874 -0.4064)
			(end 0.7874 -0.4064)
			(stroke
				(width 0.1524)
				(type default)
			)
			(layer "F.SilkS")
		)
		(fp_line
			(start 0.67945 0.3048)
			(end 0.120396 0.3048)
			(stroke
				(width 0.1)
				(type default)
			)
			(layer "F.Fab")
		)
		(fp_line
			(start 0.67945 -0.3048)
			(end 0.67945 0.3048)
			(stroke
				(width 0.1)
				(type default)
			)
			(layer "F.Fab")
		)
		(fp_line
			(start 0.12065 -0.2794)
			(end 0.12065 -0.3048)
			(stroke
				(width 0.1)
				(type default)
			)
			(layer "F.Fab")
		)
		(fp_line
			(start 0.12065 -0.3048)
			(end 0.67945 -0.3048)
			(stroke
				(width 0.1)
				(type default)
			)
			(layer "F.Fab")
		)
		(fp_line
			(start 0.120396 0.3048)
			(end 0.120396 0.2794)
			(stroke
				(width 0.1)
				(type default)
			)
			(layer "F.Fab")
		)
		(fp_line
			(start 0.120396 0.2794)
			(end -0.12065 0.2794)
			(stroke
				(width 0.1)
				(type default)
			)
			(layer "F.Fab")
		)
		(fp_line
			(start -0.12065 0.3048)
			(end -0.67945 0.3048)
			(stroke
				(width 0.1)
				(type default)
			)
			(layer "F.Fab")
		)
		(fp_line
			(start -0.12065 0.2794)
			(end -0.12065 0.3048)
			(stroke
				(width 0.1)
				(type default)
			)
			(layer "F.Fab")
		)
		(fp_line
			(start -0.12065 -0.2794)
			(end 0.12065 -0.2794)
			(stroke
				(width 0.1)
				(type default)
			)
			(layer "F.Fab")
		)
		(fp_line
			(start -0.12065 -0.305054)
			(end -0.12065 -0.2794)
			(stroke
				(width 0.1)
				(type default)
			)
			(layer "F.Fab")
		)
		(fp_line
			(start -0.67945 0.3048)
			(end -0.67945 -0.305054)
			(stroke
				(width 0.1)
				(type default)
			)
			(layer "F.Fab")
		)
		(fp_line
			(start -0.67945 -0.305054)
			(end -0.12065 -0.305054)
			(stroke
				(width 0.1)
				(type default)
			)
			(layer "F.Fab")
		)
		(pad "1" smd circle
			(at -0.40005 0 180)
			(size 0 0)
			(layers "F.Cu" "F.Mask" "F.Paste")
			(net "P12V_OCP_SFF_EN")
		)
		(pad "2" smd circle
			(at 0.40005 0 180)
			(size 0 0)
			(layers "F.Cu" "F.Mask" "F.Paste")
			(net "P12V_OCP_SFF_EN_R")
		)
	)
	(footprint ""
		(layer "F.Cu")
		(at 94.237302 -375.49963 -90)
		(property "Reference" "C721"
			(at 0 0 270)
			(layer "F.SilkS")
			(hide yes)
			(effects
				(font
					(size 1.27 1.27)
				)
			)
		)
		(property "Value" ""
			(at 0 0 270)
			(layer "F.Fab")
			(effects
				(font
					(size 1.27 1.27)
				)
			)
		)
		(duplicate_pad_numbers_are_jumpers no)
		(fp_line
			(start -0.299974 0.150114)
			(end -0.299974 -0.150114)
			(stroke
				(width 0.1)
				(type default)
			)
			(layer "F.Fab")
		)
		(fp_line
			(start 0.299974 0.150114)
			(end -0.299974 0.150114)
			(stroke
				(width 0.1)
				(type default)
			)
			(layer "F.Fab")
		)
		(fp_line
			(start -0.299974 -0.150114)
			(end 0.299974 -0.150114)
			(stroke
				(width 0.1)
				(type default)
			)
			(layer "F.Fab")
		)
		(fp_line
			(start 0.299974 -0.150114)
			(end 0.299974 0.150114)
			(stroke
				(width 0.1)
				(type default)
			)
			(layer "F.Fab")
		)
		(pad "1" smd rect
			(at -0.2667 0 270)
			(size 0.3048 0.381)
			(layers "F.Cu" "F.Mask" "F.Paste")
			(net "P5E_CPU1_P1_TX_C_DP<10>")
		)
		(pad "2" smd rect
			(at 0.2667 0 270)
			(size 0.3048 0.381)
			(layers "F.Cu" "F.Mask" "F.Paste")
			(net "P5E_CPU1_P1_TX_DP<10>")
		)
	)
)
